# BASEBOARD_FAB2 (Tioga Pass) — schematic netlist excerpt (pin names and nets, part order shuffled) for the footprints in the layout excerpt that follows; sources: Cadence DE-HDL packaged netlist, KiCad conversion of Wiwynn_Tioga_Pass_MB.brd

R9G29  RES  0.0 5% CHIP  pkg 0402  page 152 : A = H_CPU0_MEMDEF_MEMHOT_LVT3_N ; B = H_CPU0_MEMDEF_MEMHOT_LVT3_BMC_N
C25W34  CAP_A  0.1UF 16V 10% X7R  pkg 0402V  page 149 : A = VCC_DACAV3V3 ; B = GND
C1R17  CAP  10UF 6.3V 20% X6S  pkg 0603  page 139 : A = P1V5_LAN ; B = GND

(kicad_pcb
	(version 20260206)
	(generator "pcbnew")
	(generator_version "10.0")
	(general
		(thickness 1.6)
		(legacy_teardrops no)
	)
	(paper "A4")
	(title_block
		(title "Wiwynn_Tioga_Pass_MB.brd")
		(comment 1 "Tioga Pass / footprints 3065-3067 of 4770")
	)
	(layers
		(0 "F.Cu" signal "TOP")
		(4 "In1.Cu" signal "L2GND")
		(6 "In2.Cu" signal "L3")
		(8 "In3.Cu" signal "L4GND")
		(10 "In4.Cu" signal "L5")
		(12 "In5.Cu" signal "L6GND")
		(14 "In6.Cu" signal "L7VCC")
		(16 "In7.Cu" signal "L8VCC")
		(18 "In8.Cu" signal "L9GND")
		(20 "In9.Cu" signal "L10")
		(22 "In10.Cu" signal "L11GND")
		(24 "In11.Cu" signal "L12")
		(26 "In12.Cu" signal "L13GND")
		(2 "B.Cu" signal "BOTTOM")
		(9 "F.Adhes" user "F.Adhesive")
		(11 "B.Adhes" user "B.Adhesive")
		(13 "F.Paste" user "Package Geometry/Pastemask Top")
		(15 "B.Paste" user "Package Geometry/Pastemask Bottom")
		(5 "F.SilkS" user "Ref Des/Silkscreen Top")
		(7 "B.SilkS" user "Ref Des/Silkscreen Bottom")
		(1 "F.Mask" user "Board Geometry/Soldermask Top")
		(3 "B.Mask" user "Board Geometry/Soldermask Bottom")
		(17 "Dwgs.User" user "User.Drawings")
		(19 "Cmts.User" user "User.Comments")
		(21 "Eco1.User" user "User.Eco1")
		(23 "Eco2.User" user "User.Eco2")
		(25 "Edge.Cuts" user "Board Geometry/Outline")
		(27 "Margin" user)
		(31 "F.CrtYd" user "Package Geometry/Place Bound Top")
		(29 "B.CrtYd" user "Package Geometry/Place Bound Bottom")
		(35 "F.Fab" user "Ref Des/Assembly Top")
		(33 "B.Fab" user "Ref Des/Assembly Bottom")
	)
	(footprint ""
		(layer "B.Cu")
		(at 404.204424 -32.801052)
		(property "Reference" "C25W34"
			(at 0.8382 -0.67818 0)
			(unlocked yes)
			(layer "B.SilkS")
			(effects
				(font
					(size 0.4064 0.254)
					(thickness 0.1524)
				)
				(justify left mirror)
			)
		)
		(property "Value" ""
			(at 0 0 0)
			(layer "B.Fab")
			(effects
				(font
					(size 1.27 1.27)
				)
				(justify mirror)
			)
		)
		(duplicate_pad_numbers_are_jumpers no)
		(fp_poly
			(pts
				(xy -0.3048 -0.1016) (xy -0.3048 0.9906) (xy 0.3048 0.9906) (xy 0.3048 -0.1016)
			)
			(stroke
				(width 0)
				(type default)
			)
			(fill no)
			(layer "B.CrtYd")
		)
		(fp_line
			(start -0.3048 -0.1016)
			(end 0.3048 -0.1016)
			(stroke
				(width 0.1)
				(type default)
			)
			(layer "B.Fab")
		)
		(fp_line
			(start -0.3048 0.9906)
			(end -0.3048 -0.1016)
			(stroke
				(width 0.1)
				(type default)
			)
			(layer "B.Fab")
		)
		(fp_line
			(start 0.3048 -0.1016)
			(end 0.3048 0.9906)
			(stroke
				(width 0.1)
				(type default)
			)
			(layer "B.Fab")
		)
		(fp_line
			(start 0.3048 0.9906)
			(end -0.3048 0.9906)
			(stroke
				(width 0.1)
				(type default)
			)
			(layer "B.Fab")
		)
		(pad "1" smd rect
			(at 0 0 180)
			(size 0.508 0.508)
			(layers "B.Cu" "B.Mask" "B.Paste")
			(net "VCC_DACAV3V3")
		)
		(pad "2" smd rect
			(at 0 0.889 180)
			(size 0.508 0.508)
			(layers "B.Cu" "B.Mask" "B.Paste")
			(net "GND")
		)
		(zone
			(layer "B.Cu")
			(hatch none 0.5)
			(connect_pads
				(clearance 0)
			)
			(min_thickness 0.25)
			(keepout
				(tracks allowed)
				(vias not_allowed)
				(pads allowed)
				(copperpour not_allowed)
				(footprints allowed)
			)
			(placement
				(enabled no)
				(sheetname "")
			)
			(fill
				(thermal_gap 0.5)
				(thermal_bridge_width 0.5)
				(island_removal_mode 0)
			)
			(polygon
				(pts
					(xy 404.458424 -32.547052) (xy 403.950424 -32.547052) (xy 403.950424 -32.166052) (xy 404.458424 -32.166052)
				)
			)
		)
		(zone
			(layer "B.Cu")
			(hatch none 0.5)
			(connect_pads
				(clearance 0)
			)
			(min_thickness 0.25)
			(keepout
				(tracks not_allowed)
				(vias allowed)
				(pads allowed)
				(copperpour not_allowed)
				(footprints allowed)
			)
			(placement
				(enabled no)
				(sheetname "")
			)
			(fill
				(thermal_gap 0.5)
				(thermal_bridge_width 0.5)
				(island_removal_mode 0)
			)
			(polygon
				(pts
					(xy 404.458424 -32.166052) (xy 403.950424 -32.166052) (xy 403.950424 -32.547052) (xy 404.458424 -32.547052)
				)
			)
		)
	)
	(footprint ""
		(layer "B.Cu")
		(at 425.5008 -14.1732 -90)
		(property "Reference" "R9G29"
			(at 0 0 90)
			(layer "B.SilkS")
			(hide yes)
			(effects
				(font
					(size 1.27 1.27)
				)
				(justify mirror)
			)
		)
		(property "Value" ""
			(at 0 0 90)
			(layer "B.Fab")
			(effects
				(font
					(size 1.27 1.27)
				)
				(justify mirror)
			)
		)
		(duplicate_pad_numbers_are_jumpers no)
		(fp_poly
			(pts
				(xy 0.2794 -0.101854) (xy -0.279654 -0.101854) (xy -0.2794 0.990346) (xy 0.279146 0.990346)
			)
			(stroke
				(width 0)
				(type default)
			)
			(fill no)
			(layer "B.CrtYd")
		)
		(fp_line
			(start -0.2794 0.990346)
			(end -0.279654 -0.101854)
			(stroke
				(width 0.1)
				(type default)
			)
			(layer "B.Fab")
		)
		(fp_line
			(start 0.279146 0.990346)
			(end -0.2794 0.990346)
			(stroke
				(width 0.1)
				(type default)
			)
			(layer "B.Fab")
		)
		(fp_line
			(start -0.279654 -0.101854)
			(end 0.2794 -0.101854)
			(stroke
				(width 0.1)
				(type default)
			)
			(layer "B.Fab")
		)
		(fp_line
			(start 0.2794 -0.101854)
			(end 0.279146 0.990346)
			(stroke
				(width 0.1)
				(type default)
			)
			(layer "B.Fab")
		)
		(pad "1" smd rect
			(at 0 0 90)
			(size 0.508 0.508)
			(layers "B.Cu" "B.Mask" "B.Paste")
			(net "H_CPU0_MEMDEF_MEMHOT_LVT3_N")
		)
		(pad "2" smd rect
			(at 0 0.889 90)
			(size 0.508 0.508)
			(layers "B.Cu" "B.Mask" "B.Paste")
			(net "H_CPU0_MEMDEF_MEMHOT_LVT3_BMC_N")
		)
		(zone
			(layer "B.Cu")
			(hatch none 0.5)
			(connect_pads
				(clearance 0)
			)
			(min_thickness 0.25)
			(keepout
				(tracks not_allowed)
				(vias allowed)
				(pads allowed)
				(copperpour not_allowed)
				(footprints allowed)
			)
			(placement
				(enabled no)
				(sheetname "")
			)
			(fill
				(thermal_gap 0.5)
				(thermal_bridge_width 0.5)
				(island_removal_mode 0)
			)
			(polygon
				(pts
					(xy 424.866054 -13.9192) (xy 424.866054 -14.427454) (xy 425.247054 -14.4272) (xy 425.247054 -13.9192)
				)
			)
		)
		(zone
			(layer "B.Cu")
			(hatch none 0.5)
			(connect_pads
				(clearance 0)
			)
			(min_thickness 0.25)
			(keepout
				(tracks allowed)
				(vias not_allowed)
				(pads allowed)
				(copperpour not_allowed)
				(footprints allowed)
			)
			(placement
				(enabled no)
				(sheetname "")
			)
			(fill
				(thermal_gap 0.5)
				(thermal_bridge_width 0.5)
				(island_removal_mode 0)
			)
			(polygon
				(pts
					(xy 425.247054 -13.9192) (xy 425.247054 -14.4272) (xy 424.866054 -14.427454) (xy 424.866054 -13.9192)
				)
			)
		)
	)
	(footprint ""
		(layer "B.Cu")
		(at 480.2251 -45.3644 90)
		(property "Reference" "C1R17"
			(at 0 0 90)
			(layer "B.SilkS")
			(hide yes)
			(effects
				(font
					(size 1.27 1.27)
				)
				(justify mirror)
			)
		)
		(property "Value" ""
			(at 0 0 90)
			(layer "B.Fab")
			(effects
				(font
					(size 1.27 1.27)
				)
				(justify mirror)
			)
		)
		(duplicate_pad_numbers_are_jumpers no)
		(fp_poly
			(pts
				(xy 0.4953 -0.2032) (xy -0.4953 -0.2032) (xy -0.4953 1.6002) (xy 0.4953 1.6002)
			)
			(stroke
				(width 0)
				(type default)
			)
			(fill no)
			(layer "B.CrtYd")
		)
		(fp_line
			(start 0.4953 -0.2032)
			(end -0.4953 -0.2032)
			(stroke
				(width 0.1)
				(type default)
			)
			(layer "B.Fab")
		)
		(fp_line
			(start -0.4953 -0.2032)
			(end -0.4953 1.6002)
			(stroke
				(width 0.1)
				(type default)
			)
			(layer "B.Fab")
		)
		(fp_line
			(start 0.4953 1.6002)
			(end 0.4953 -0.2032)
			(stroke
				(width 0.1)
				(type default)
			)
			(layer "B.Fab")
		)
		(fp_line
			(start -0.4953 1.6002)
			(end 0.4953 1.6002)
			(stroke
				(width 0.1)
				(type default)
			)
			(layer "B.Fab")
		)
		(pad "1" smd rect
			(at 0 0 270)
			(size 0.762 0.889)
			(layers "B.Cu" "B.Mask" "B.Paste")
			(net "P1V5_LAN")
		)
		(pad "2" smd rect
			(at 0 1.397 270)
			(size 0.762 0.889)
			(layers "B.Cu" "B.Mask" "B.Paste")
			(net "GND")
		)
		(zone
			(layer "B.Cu")
			(hatch none 0.5)
			(connect_pads
				(clearance 0)
			)
			(min_thickness 0.25)
			(keepout
				(tracks not_allowed)
				(vias allowed)
				(pads allowed)
				(copperpour not_allowed)
				(footprints allowed)
			)
			(placement
				(enabled no)
				(sheetname "")
			)
			(fill
				(thermal_gap 0.5)
				(thermal_bridge_width 0.5)
				(island_removal_mode 0)
			)
			(polygon
				(pts
					(xy 480.6696 -45.7454) (xy 480.6696 -44.9834) (xy 481.1776 -44.9834) (xy 481.1776 -45.7454)
				)
			)
		)
	)
)
